# SCM (Grand Teton) — schematic netlist excerpt (pin names and nets, part order shuffled) for the footprints in the layout excerpt that follows; sources: Cadence DE-HDL packaged netlist, KiCad conversion of 12092022_DA0F0TMDCD0_F0T_Management_Board_D_brd_V3_OCP.brd

SW8  SW_PUSHBUTTON4P_12_G34_H2  SW4S_DTSAM-63N/K-S-Q-T/R MECH  pkg SW4S_DTSAM63N  page 50
  \1\  = GND
  \2\  = REAR_AC_PWR_BTN
  \3\  = GND
  \4\  = GND

(kicad_pcb
	(version 20260206)
	(generator "pcbnew")
	(generator_version "10.0")
	(general
		(thickness 1.6)
		(legacy_teardrops no)
	)
	(paper "A4")
	(title_block
		(title "12092022_DA0F0TMDCD0_F0T_Management_Board_D_brd_V3_OCP.brd")
		(comment 1 "Grand Teton / footprints 32-32 of 1440")
	)
	(layers
		(0 "F.Cu" signal "TOP")
		(4 "In1.Cu" signal "GND")
		(6 "In2.Cu" signal "IN1")
		(8 "In3.Cu" signal "GND1")
		(10 "In4.Cu" signal "IN2")
		(12 "In5.Cu" signal "VCC")
		(14 "In6.Cu" signal "VCC1")
		(16 "In7.Cu" signal "IN3")
		(18 "In8.Cu" signal "GND2")
		(20 "In9.Cu" signal "IN4")
		(22 "In10.Cu" signal "GND3")
		(2 "B.Cu" signal "BOTTOM")
		(9 "F.Adhes" user "F.Adhesive")
		(11 "B.Adhes" user "B.Adhesive")
		(13 "F.Paste" user "Package Geometry/Pastemask Top")
		(15 "B.Paste" user "Package Geometry/Pastemask Bottom")
		(5 "F.SilkS" user "Ref Des/Silkscreen Top")
		(7 "B.SilkS" user "Ref Des/Silkscreen Bottom")
		(1 "F.Mask" user "Board Geometry/Soldermask Top")
		(3 "B.Mask" user "Board Geometry/Soldermask Bottom")
		(17 "Dwgs.User" user "User.Drawings")
		(19 "Cmts.User" user "User.Comments")
		(21 "Eco1.User" user "User.Eco1")
		(23 "Eco2.User" user "User.Eco2")
		(25 "Edge.Cuts" user "Board Geometry/Outline")
		(27 "Margin" user)
		(31 "F.CrtYd" user "Package Geometry/Place Bound Top")
		(29 "B.CrtYd" user "Package Geometry/Place Bound Bottom")
		(35 "F.Fab" user "Ref Des/Assembly Top")
		(33 "B.Fab" user "Ref Des/Assembly Bottom")
	)
	(footprint ""
		(layer "F.Cu")
		(at 70.600062 -3.3401)
		(property "Reference" "SW8"
			(at -5.516626 -6.306566 0)
			(unlocked yes)
			(layer "F.SilkS")
			(effects
				(font
					(size 0.7874 0.5842)
					(thickness 0.1524)
				)
				(justify left)
			)
		)
		(property "Value" ""
			(at 0 0 0)
			(layer "F.Fab")
			(effects
				(font
					(size 1.27 1.27)
				)
			)
		)
		(duplicate_pad_numbers_are_jumpers no)
		(fp_line
			(start -3.700018 -4.549902)
			(end -3.700018 -2.51206)
			(stroke
				(width 0.1524)
				(type default)
			)
			(layer "F.SilkS")
		)
		(fp_line
			(start -3.700018 -0.98806)
			(end -3.700018 -0.88646)
			(stroke
				(width 0.1524)
				(type default)
			)
			(layer "F.SilkS")
		)
		(fp_line
			(start -3.700018 1.39954)
			(end -3.700018 1.549908)
			(stroke
				(width 0.1524)
				(type default)
			)
			(layer "F.SilkS")
		)
		(fp_line
			(start -3.700018 1.549908)
			(end -1.75006 1.549908)
			(stroke
				(width 0.1524)
				(type default)
			)
			(layer "F.SilkS")
		)
		(fp_line
			(start -3.1496 -4.549902)
			(end -3.700018 -4.549902)
			(stroke
				(width 0.1524)
				(type default)
			)
			(layer "F.SilkS")
		)
		(fp_line
			(start -1.75006 1.549908)
			(end -1.75006 4.549902)
			(stroke
				(width 0.1524)
				(type default)
			)
			(layer "F.SilkS")
		)
		(fp_line
			(start -1.75006 4.549902)
			(end 1.75006 4.549902)
			(stroke
				(width 0.1524)
				(type default)
			)
			(layer "F.SilkS")
		)
		(fp_line
			(start 1.3716 -4.549902)
			(end -1.3716 -4.549902)
			(stroke
				(width 0.1524)
				(type default)
			)
			(layer "F.SilkS")
		)
		(fp_line
			(start 1.75006 1.549908)
			(end 3.700018 1.549908)
			(stroke
				(width 0.1524)
				(type default)
			)
			(layer "F.SilkS")
		)
		(fp_line
			(start 1.75006 4.549902)
			(end 1.75006 1.549908)
			(stroke
				(width 0.1524)
				(type default)
			)
			(layer "F.SilkS")
		)
		(fp_line
			(start 3.700018 -4.549902)
			(end 3.1496 -4.549902)
			(stroke
				(width 0.1524)
				(type default)
			)
			(layer "F.SilkS")
		)
		(fp_line
			(start 3.700018 -2.51206)
			(end 3.700018 -4.549902)
			(stroke
				(width 0.1524)
				(type default)
			)
			(layer "F.SilkS")
		)
		(fp_line
			(start 3.700018 -0.88646)
			(end 3.700018 -0.98806)
			(stroke
				(width 0.1524)
				(type default)
			)
			(layer "F.SilkS")
		)
		(fp_line
			(start 3.700018 1.549908)
			(end 3.700018 1.39954)
			(stroke
				(width 0.1524)
				(type default)
			)
			(layer "F.SilkS")
		)
		(fp_poly
			(pts
				(xy -2.249932 -5.286502) (xy -2.963418 -6.713474) (xy -1.536446 -6.713474)
			)
			(stroke
				(width 0)
				(type default)
			)
			(fill yes)
			(layer "F.SilkS")
		)
		(fp_line
			(start -3.700018 -4.549902)
			(end -3.700018 1.549908)
			(stroke
				(width 0.1)
				(type default)
			)
			(layer "F.Fab")
		)
		(fp_line
			(start -3.700018 1.549908)
			(end -1.75006 1.549908)
			(stroke
				(width 0.1)
				(type default)
			)
			(layer "F.Fab")
		)
		(fp_line
			(start -1.75006 1.549908)
			(end -1.75006 4.549902)
			(stroke
				(width 0.1)
				(type default)
			)
			(layer "F.Fab")
		)
		(fp_line
			(start -1.75006 4.549902)
			(end 1.75006 4.549902)
			(stroke
				(width 0.1)
				(type default)
			)
			(layer "F.Fab")
		)
		(fp_line
			(start 1.75006 1.549908)
			(end 3.700018 1.549908)
			(stroke
				(width 0.1)
				(type default)
			)
			(layer "F.Fab")
		)
		(fp_line
			(start 1.75006 4.549902)
			(end 1.75006 1.549908)
			(stroke
				(width 0.1)
				(type default)
			)
			(layer "F.Fab")
		)
		(fp_line
			(start 3.700018 -4.549902)
			(end -3.700018 -4.549902)
			(stroke
				(width 0.1)
				(type default)
			)
			(layer "F.Fab")
		)
		(fp_line
			(start 3.700018 1.549908)
			(end 3.700018 -4.549902)
			(stroke
				(width 0.1)
				(type default)
			)
			(layer "F.Fab")
		)
		(fp_poly
			(pts
				(xy -3.883914 -4.043934) (xy -5.310886 -3.330448) (xy -5.310886 -4.75742)
			)
			(stroke
				(width 0)
				(type default)
			)
			(fill yes)
			(layer "F.Fab")
		)
		(pad "" np_thru_hole circle
			(at -3.50012 -1.75006)
			(size 0.9144 0.9144)
			(drill 0.9144)
			(layers "*.Cu" "*.Mask")
			(clearance 0.381)
			(thermal_gap 0.381)
		)
		(pad "" np_thru_hole circle
			(at 3.50012 -1.75006)
			(size 0.9144 0.9144)
			(drill 0.9144)
			(layers "*.Cu" "*.Mask")
			(clearance 0.381)
			(thermal_gap 0.381)
		)
		(pad "1" smd rect
			(at -2.249932 -4.05003)
			(size 1.4986 2.0066)
			(layers "F.Cu" "F.Mask" "F.Paste")
			(net "GND")
		)
		(pad "2" smd rect
			(at 2.249932 -4.05003)
			(size 1.4986 2.0066)
			(layers "F.Cu" "F.Mask" "F.Paste")
			(net "REAR_AC_PWR_BTN")
		)
		(pad "3" smd rect
			(at -4.19989 0.249936)
			(size 2.0066 2.0066)
			(layers "F.Cu" "F.Mask" "F.Paste")
			(net "GND")
		)
		(pad "4" smd rect
			(at 4.19989 0.249936)
			(size 2.0066 2.0066)
			(layers "F.Cu" "F.Mask" "F.Paste")
			(net "GND")
		)
		(zone
			(layers "F.Cu" "B.Cu" "In1.Cu" "In2.Cu" "In3.Cu" "In4.Cu" "In5.Cu" "In6.Cu"
				"In7.Cu" "In8.Cu" "In9.Cu" "In10.Cu"
			)
			(hatch none 0.5)
			(connect_pads
				(clearance 0)
			)
			(min_thickness 0.25)
			(keepout
				(tracks not_allowed)
				(vias allowed)
				(pads allowed)
				(copperpour not_allowed)
				(footprints allowed)
			)
			(placement
				(enabled no)
				(sheetname "")
			)
			(fill
				(thermal_gap 0.5)
				(thermal_bridge_width 0.5)
				(island_removal_mode 0)
			)
			(polygon
				(pts
					(arc
						(start 67.963796 -5.09016)
						(mid 66.236088 -5.09016)
						(end 67.963796 -5.09016)
					)
				)
			)
		)
		(zone
			(layers "F.Cu" "B.Cu" "In1.Cu" "In2.Cu" "In3.Cu" "In4.Cu" "In5.Cu" "In6.Cu"
				"In7.Cu" "In8.Cu" "In9.Cu" "In10.Cu"
			)
			(hatch none 0.5)
			(connect_pads
				(clearance 0)
			)
			(min_thickness 0.25)
			(keepout
				(tracks not_allowed)
				(vias allowed)
				(pads allowed)
				(copperpour not_allowed)
				(footprints allowed)
			)
			(placement
				(enabled no)
				(sheetname "")
			)
			(fill
				(thermal_gap 0.5)
				(thermal_bridge_width 0.5)
				(island_removal_mode 0)
			)
			(polygon
				(pts
					(arc
						(start 74.963782 -5.09016)
						(mid 73.236582 -5.09016)
						(end 74.963782 -5.09016)
					)
				)
			)
		)
	)
)
